(kicad_pcb
	(version 20260206)
	(generator "pcbnew")
	(generator_version "10.0")
	(general
		(thickness 1.6)
		(legacy_teardrops no)
	)
	(paper "A4")
	(title_block
		(title "01162023_DA0F0TEBIF0_F0T_Expander_BD_F_brd_V02_OCP.brd")
		(comment 1 "Grand Teton / footprints 8309-8316 of 9728")
	)
	(layers
		(0 "F.Cu" signal "TOP")
		(4 "In1.Cu" signal "GND")
		(6 "In2.Cu" signal "VCC")
		(8 "In3.Cu" signal "VCC1")
		(10 "In4.Cu" signal "GND1")
		(12 "In5.Cu" signal "IN1")
		(14 "In6.Cu" signal "GND2")
		(16 "In7.Cu" signal "IN2")
		(18 "In8.Cu" signal "GND3")
		(20 "In9.Cu" signal "IN3")
		(22 "In10.Cu" signal "GND4")
		(24 "In11.Cu" signal "IN4")
		(26 "In12.Cu" signal "GND5")
		(28 "In13.Cu" signal "IN5")
		(30 "In14.Cu" signal "GND6")
		(32 "In15.Cu" signal "IN6")
		(34 "In16.Cu" signal "GND7")
		(2 "B.Cu" signal "BOTTOM")
		(9 "F.Adhes" user "F.Adhesive")
		(11 "B.Adhes" user "B.Adhesive")
		(13 "F.Paste" user "Package Geometry/Pastemask Top")
		(15 "B.Paste" user "Package Geometry/Pastemask Bottom")
		(5 "F.SilkS" user "Ref Des/Silkscreen Top")
		(7 "B.SilkS" user "Ref Des/Silkscreen Bottom")
		(1 "F.Mask" user "Board Geometry/Soldermask Top")
		(3 "B.Mask" user "Board Geometry/Soldermask Bottom")
		(17 "Dwgs.User" user "User.Drawings")
		(19 "Cmts.User" user "User.Comments")
		(21 "Eco1.User" user "User.Eco1")
		(23 "Eco2.User" user "User.Eco2")
		(25 "Edge.Cuts" user "Board Geometry/Outline")
		(27 "Margin" user)
		(31 "F.CrtYd" user "Package Geometry/Place Bound Top")
		(29 "B.CrtYd" user "Package Geometry/Place Bound Bottom")
		(35 "F.Fab" user "Ref Des/Assembly Top")
		(33 "B.Fab" user "Ref Des/Assembly Bottom")
	)
	(footprint ""
		(layer "B.Cu")
		(at 341.294212 -217.187018 -90)
		(property "Reference" "C2059"
			(at 0 0 90)
			(layer "B.SilkS")
			(hide yes)
			(effects
				(font
					(size 1.27 1.27)
				)
				(justify mirror)
			)
		)
		(property "Value" ""
			(at 0 0 90)
			(layer "B.Fab")
			(effects
				(font
					(size 1.27 1.27)
				)
				(justify mirror)
			)
		)
		(duplicate_pad_numbers_are_jumpers no)
		(fp_line
			(start -0.69215 0.2921)
			(end 0.69215 0.2921)
			(stroke
				(width 0.1524)
				(type default)
			)
			(layer "B.SilkS")
		)
		(fp_line
			(start 0.69215 0.2921)
			(end 0.69215 -0.2921)
			(stroke
				(width 0.1524)
				(type default)
			)
			(layer "B.SilkS")
		)
		(fp_line
			(start -0.69215 -0.2921)
			(end -0.69215 0.2921)
			(stroke
				(width 0.1524)
				(type default)
			)
			(layer "B.SilkS")
		)
		(fp_line
			(start 0.69215 -0.2921)
			(end -0.69215 -0.2921)
			(stroke
				(width 0.1524)
				(type default)
			)
			(layer "B.SilkS")
		)
		(fp_line
			(start -0.51435 0.2794)
			(end 0.51435 0.2794)
			(stroke
				(width 0.1)
				(type default)
			)
			(layer "B.Fab")
		)
		(fp_line
			(start 0.51435 0.2794)
			(end 0.51435 -0.2794)
			(stroke
				(width 0.1)
				(type default)
			)
			(layer "B.Fab")
		)
		(fp_line
			(start -0.51435 -0.2794)
			(end -0.51435 0.2794)
			(stroke
				(width 0.1)
				(type default)
			)
			(layer "B.Fab")
		)
		(fp_line
			(start 0.51435 -0.2794)
			(end -0.51435 -0.2794)
			(stroke
				(width 0.1)
				(type default)
			)
			(layer "B.Fab")
		)
		(pad "1" smd circle
			(at 0.40005 0 90)
			(size 0 0)
			(layers "B.Cu" "B.Mask" "B.Paste")
			(net "P3V3_FPGA_VCCIO2")
		)
		(pad "2" smd circle
			(at -0.40005 0 90)
			(size 0 0)
			(layers "B.Cu" "B.Mask" "B.Paste")
			(net "GND")
		)
		(zone
			(layer "B.Cu")
			(hatch none 0.5)
			(connect_pads
				(clearance 0)
			)
			(min_thickness 0.25)
			(keepout
				(tracks not_allowed)
				(vias allowed)
				(pads allowed)
				(copperpour not_allowed)
				(footprints allowed)
			)
			(placement
				(enabled no)
				(sheetname "")
			)
			(fill
				(thermal_gap 0.5)
				(thermal_bridge_width 0.5)
				(island_removal_mode 0)
			)
			(polygon
				(pts
					(xy 341.206582 -216.996518) (xy 341.148416 -217.087958) (xy 341.148416 -217.287348) (xy 341.206582 -217.377518)
					(xy 341.381842 -217.377518) (xy 341.440262 -217.287348) (xy 341.440262 -217.087958) (xy 341.382096 -216.996518)
				)
			)
		)
	)
	(footprint ""
		(layer "B.Cu")
		(at 15.742666 -387.531356 180)
		(property "Reference" "C4468"
			(at 0 0 0)
			(layer "B.SilkS")
			(hide yes)
			(effects
				(font
					(size 1.27 1.27)
				)
				(justify mirror)
			)
		)
		(property "Value" ""
			(at 0 0 0)
			(layer "B.Fab")
			(effects
				(font
					(size 1.27 1.27)
				)
				(justify mirror)
			)
		)
		(duplicate_pad_numbers_are_jumpers no)
		(fp_line
			(start 0.7874 0.4064)
			(end 0.7874 -0.4064)
			(stroke
				(width 0.1524)
				(type default)
			)
			(layer "B.SilkS")
		)
		(fp_line
			(start 0.7874 -0.4064)
			(end -0.7874 -0.4064)
			(stroke
				(width 0.1524)
				(type default)
			)
			(layer "B.SilkS")
		)
		(fp_line
			(start -0.7874 0.4064)
			(end 0.7874 0.4064)
			(stroke
				(width 0.1524)
				(type default)
			)
			(layer "B.SilkS")
		)
		(fp_line
			(start -0.7874 -0.4064)
			(end -0.7874 0.4064)
			(stroke
				(width 0.1524)
				(type default)
			)
			(layer "B.SilkS")
		)
		(fp_line
			(start 0.67945 0.3048)
			(end 0.67945 -0.305054)
			(stroke
				(width 0.1)
				(type default)
			)
			(layer "B.Fab")
		)
		(fp_line
			(start 0.67945 -0.305054)
			(end 0.12065 -0.305054)
			(stroke
				(width 0.1)
				(type default)
			)
			(layer "B.Fab")
		)
		(fp_line
			(start 0.12065 0.3048)
			(end 0.67945 0.3048)
			(stroke
				(width 0.1)
				(type default)
			)
			(layer "B.Fab")
		)
		(fp_line
			(start 0.12065 0.2794)
			(end 0.12065 0.3048)
			(stroke
				(width 0.1)
				(type default)
			)
			(layer "B.Fab")
		)
		(fp_line
			(start 0.12065 -0.2794)
			(end -0.12065 -0.2794)
			(stroke
				(width 0.1)
				(type default)
			)
			(layer "B.Fab")
		)
		(fp_line
			(start 0.12065 -0.305054)
			(end 0.12065 -0.2794)
			(stroke
				(width 0.1)
				(type default)
			)
			(layer "B.Fab")
		)
		(fp_line
			(start -0.120396 0.3048)
			(end -0.120396 0.2794)
			(stroke
				(width 0.1)
				(type default)
			)
			(layer "B.Fab")
		)
		(fp_line
			(start -0.120396 0.2794)
			(end 0.12065 0.2794)
			(stroke
				(width 0.1)
				(type default)
			)
			(layer "B.Fab")
		)
		(fp_line
			(start -0.12065 -0.2794)
			(end -0.12065 -0.3048)
			(stroke
				(width 0.1)
				(type default)
			)
			(layer "B.Fab")
		)
		(fp_line
			(start -0.12065 -0.3048)
			(end -0.67945 -0.3048)
			(stroke
				(width 0.1)
				(type default)
			)
			(layer "B.Fab")
		)
		(fp_line
			(start -0.67945 0.3048)
			(end -0.120396 0.3048)
			(stroke
				(width 0.1)
				(type default)
			)
			(layer "B.Fab")
		)
		(fp_line
			(start -0.67945 -0.3048)
			(end -0.67945 0.3048)
			(stroke
				(width 0.1)
				(type default)
			)
			(layer "B.Fab")
		)
		(pad "1" smd circle
			(at 0.40005 0)
			(size 0 0)
			(layers "B.Cu" "B.Mask" "B.Paste")
			(net "P1V2_USB_8042")
		)
		(pad "2" smd circle
			(at -0.40005 0)
			(size 0 0)
			(layers "B.Cu" "B.Mask" "B.Paste")
			(net "GND")
		)
	)
	(footprint ""
		(layer "B.Cu")
		(at 278.549862 -290.215066)
		(property "Reference" "C3353"
			(at 0 0 0)
			(layer "B.SilkS")
			(hide yes)
			(effects
				(font
					(size 1.27 1.27)
				)
				(justify mirror)
			)
		)
		(property "Value" ""
			(at 0 0 0)
			(layer "B.Fab")
			(effects
				(font
					(size 1.27 1.27)
				)
				(justify mirror)
			)
		)
		(duplicate_pad_numbers_are_jumpers no)
		(fp_line
			(start -0.299974 -0.150114)
			(end -0.299974 0.150114)
			(stroke
				(width 0.1)
				(type default)
			)
			(layer "B.Fab")
		)
		(fp_line
			(start -0.299974 0.150114)
			(end 0.299974 0.150114)
			(stroke
				(width 0.1)
				(type default)
			)
			(layer "B.Fab")
		)
		(fp_line
			(start 0.299974 -0.150114)
			(end -0.299974 -0.150114)
			(stroke
				(width 0.1)
				(type default)
			)
			(layer "B.Fab")
		)
		(fp_line
			(start 0.299974 0.150114)
			(end 0.299974 -0.150114)
			(stroke
				(width 0.1)
				(type default)
			)
			(layer "B.Fab")
		)
		(pad "1" smd rect
			(at 0.2667 0 180)
			(size 0.3048 0.381)
			(layers "B.Cu" "B.Mask" "B.Paste")
			(net "P1V8_PEX")
		)
		(pad "2" smd rect
			(at -0.2667 0 180)
			(size 0.3048 0.381)
			(layers "B.Cu" "B.Mask" "B.Paste")
			(net "GND")
		)
	)
	(footprint ""
		(layer "B.Cu")
		(at 252.0188 -348.8436 180)
		(property "Reference" "PR7162"
			(at 0 0 0)
			(layer "B.SilkS")
			(hide yes)
			(effects
				(font
					(size 1.27 1.27)
				)
				(justify mirror)
			)
		)
		(property "Value" ""
			(at 0 0 0)
			(layer "B.Fab")
			(effects
				(font
					(size 1.27 1.27)
				)
				(justify mirror)
			)
		)
		(duplicate_pad_numbers_are_jumpers no)
		(fp_line
			(start 0.7874 0.4064)
			(end 0.7874 -0.4064)
			(stroke
				(width 0.1524)
				(type default)
			)
			(layer "B.SilkS")
		)
		(fp_line
			(start 0.7874 -0.4064)
			(end -0.7874 -0.4064)
			(stroke
				(width 0.1524)
				(type default)
			)
			(layer "B.SilkS")
		)
		(fp_line
			(start -0.7874 0.4064)
			(end 0.7874 0.4064)
			(stroke
				(width 0.1524)
				(type default)
			)
			(layer "B.SilkS")
		)
		(fp_line
			(start -0.7874 -0.4064)
			(end -0.7874 0.4064)
			(stroke
				(width 0.1524)
				(type default)
			)
			(layer "B.SilkS")
		)
		(fp_line
			(start 0.67945 0.3048)
			(end 0.67945 -0.305054)
			(stroke
				(width 0.1)
				(type default)
			)
			(layer "B.Fab")
		)
		(fp_line
			(start 0.67945 -0.305054)
			(end 0.12065 -0.305054)
			(stroke
				(width 0.1)
				(type default)
			)
			(layer "B.Fab")
		)
		(fp_line
			(start 0.12065 0.3048)
			(end 0.67945 0.3048)
			(stroke
				(width 0.1)
				(type default)
			)
			(layer "B.Fab")
		)
		(fp_line
			(start 0.12065 0.2794)
			(end 0.12065 0.3048)
			(stroke
				(width 0.1)
				(type default)
			)
			(layer "B.Fab")
		)
		(fp_line
			(start 0.12065 -0.2794)
			(end -0.12065 -0.2794)
			(stroke
				(width 0.1)
				(type default)
			)
			(layer "B.Fab")
		)
		(fp_line
			(start 0.12065 -0.305054)
			(end 0.12065 -0.2794)
			(stroke
				(width 0.1)
				(type default)
			)
			(layer "B.Fab")
		)
		(fp_line
			(start -0.120396 0.3048)
			(end -0.120396 0.2794)
			(stroke
				(width 0.1)
				(type default)
			)
			(layer "B.Fab")
		)
		(fp_line
			(start -0.120396 0.2794)
			(end 0.12065 0.2794)
			(stroke
				(width 0.1)
				(type default)
			)
			(layer "B.Fab")
		)
		(fp_line
			(start -0.12065 -0.2794)
			(end -0.12065 -0.3048)
			(stroke
				(width 0.1)
				(type default)
			)
			(layer "B.Fab")
		)
		(fp_line
			(start -0.12065 -0.3048)
			(end -0.67945 -0.3048)
			(stroke
				(width 0.1)
				(type default)
			)
			(layer "B.Fab")
		)
		(fp_line
			(start -0.67945 0.3048)
			(end -0.120396 0.3048)
			(stroke
				(width 0.1)
				(type default)
			)
			(layer "B.Fab")
		)
		(fp_line
			(start -0.67945 -0.3048)
			(end -0.67945 0.3048)
			(stroke
				(width 0.1)
				(type default)
			)
			(layer "B.Fab")
		)
		(pad "1" smd circle
			(at 0.40005 0)
			(size 0 0)
			(layers "B.Cu" "B.Mask" "B.Paste")
			(net "P12V_HSC_EN")
		)
		(pad "2" smd circle
			(at -0.40005 0)
			(size 0 0)
			(layers "B.Cu" "B.Mask" "B.Paste")
			(net "HSC_P12V_EN")
		)
	)
	(footprint ""
		(layer "B.Cu")
		(at 167.675052 -293.99992 -90)
		(property "Reference" "C1387"
			(at 0 0 90)
			(layer "B.SilkS")
			(hide yes)
			(effects
				(font
					(size 1.27 1.27)
				)
				(justify mirror)
			)
		)
		(property "Value" ""
			(at 0 0 90)
			(layer "B.Fab")
			(effects
				(font
					(size 1.27 1.27)
				)
				(justify mirror)
			)
		)
		(duplicate_pad_numbers_are_jumpers no)
		(fp_line
			(start -0.299974 0.150114)
			(end 0.299974 0.150114)
			(stroke
				(width 0.1)
				(type default)
			)
			(layer "B.Fab")
		)
		(fp_line
			(start 0.299974 0.150114)
			(end 0.299974 -0.150114)
			(stroke
				(width 0.1)
				(type default)
			)
			(layer "B.Fab")
		)
		(fp_line
			(start -0.299974 -0.150114)
			(end -0.299974 0.150114)
			(stroke
				(width 0.1)
				(type default)
			)
			(layer "B.Fab")
		)
		(fp_line
			(start 0.299974 -0.150114)
			(end -0.299974 -0.150114)
			(stroke
				(width 0.1)
				(type default)
			)
			(layer "B.Fab")
		)
		(pad "1" smd rect
			(at 0.2667 0 90)
			(size 0.3048 0.381)
			(layers "B.Cu" "B.Mask" "B.Paste")
			(net "P0V8_PEX1")
		)
		(pad "2" smd rect
			(at -0.2667 0 90)
			(size 0.3048 0.381)
			(layers "B.Cu" "B.Mask" "B.Paste")
			(net "GND")
		)
	)
	(footprint ""
		(layer "B.Cu")
		(at 225.556064 -208.78546 -90)
		(property "Reference" "R5288"
			(at 0 0 90)
			(layer "B.SilkS")
			(hide yes)
			(effects
				(font
					(size 1.27 1.27)
				)
				(justify mirror)
			)
		)
		(property "Value" ""
			(at 0 0 90)
			(layer "B.Fab")
			(effects
				(font
					(size 1.27 1.27)
				)
				(justify mirror)
			)
		)
		(duplicate_pad_numbers_are_jumpers no)
		(fp_line
			(start -0.7874 0.4064)
			(end 0.7874 0.4064)
			(stroke
				(width 0.1524)
				(type default)
			)
			(layer "B.SilkS")
		)
		(fp_line
			(start 0.7874 0.4064)
			(end 0.7874 -0.4064)
			(stroke
				(width 0.1524)
				(type default)
			)
			(layer "B.SilkS")
		)
		(fp_line
			(start -0.7874 -0.4064)
			(end -0.7874 0.4064)
			(stroke
				(width 0.1524)
				(type default)
			)
			(layer "B.SilkS")
		)
		(fp_line
			(start 0.7874 -0.4064)
			(end -0.7874 -0.4064)
			(stroke
				(width 0.1524)
				(type default)
			)
			(layer "B.SilkS")
		)
		(fp_line
			(start -0.67945 0.3048)
			(end -0.120396 0.3048)
			(stroke
				(width 0.1)
				(type default)
			)
			(layer "B.Fab")
		)
		(fp_line
			(start -0.120396 0.3048)
			(end -0.120396 0.2794)
			(stroke
				(width 0.1)
				(type default)
			)
			(layer "B.Fab")
		)
		(fp_line
			(start 0.12065 0.3048)
			(end 0.67945 0.3048)
			(stroke
				(width 0.1)
				(type default)
			)
			(layer "B.Fab")
		)
		(fp_line
			(start 0.67945 0.3048)
			(end 0.67945 -0.305054)
			(stroke
				(width 0.1)
				(type default)
			)
			(layer "B.Fab")
		)
		(fp_line
			(start -0.120396 0.2794)
			(end 0.12065 0.2794)
			(stroke
				(width 0.1)
				(type default)
			)
			(layer "B.Fab")
		)
		(fp_line
			(start 0.12065 0.2794)
			(end 0.12065 0.3048)
			(stroke
				(width 0.1)
				(type default)
			)
			(layer "B.Fab")
		)
		(fp_line
			(start -0.12065 -0.2794)
			(end -0.12065 -0.3048)
			(stroke
				(width 0.1)
				(type default)
			)
			(layer "B.Fab")
		)
		(fp_line
			(start 0.12065 -0.2794)
			(end -0.12065 -0.2794)
			(stroke
				(width 0.1)
				(type default)
			)
			(layer "B.Fab")
		)
		(fp_line
			(start -0.67945 -0.3048)
			(end -0.67945 0.3048)
			(stroke
				(width 0.1)
				(type default)
			)
			(layer "B.Fab")
		)
		(fp_line
			(start -0.12065 -0.3048)
			(end -0.67945 -0.3048)
			(stroke
				(width 0.1)
				(type default)
			)
			(layer "B.Fab")
		)
		(fp_line
			(start 0.12065 -0.305054)
			(end 0.12065 -0.2794)
			(stroke
				(width 0.1)
				(type default)
			)
			(layer "B.Fab")
		)
		(fp_line
			(start 0.67945 -0.305054)
			(end 0.12065 -0.305054)
			(stroke
				(width 0.1)
				(type default)
			)
			(layer "B.Fab")
		)
		(pad "1" smd circle
			(at 0.40005 0 90)
			(size 0 0)
			(layers "B.Cu" "B.Mask" "B.Paste")
			(net "RST_SMB_FIO_R_N")
		)
		(pad "2" smd circle
			(at -0.40005 0 90)
			(size 0 0)
			(layers "B.Cu" "B.Mask" "B.Paste")
			(net "RST_SMB_FIO_N")
		)
	)
	(footprint ""
		(layer "B.Cu")
		(at 299.067474 -221.694502 90)
		(property "Reference" "R1865"
			(at 0 0 90)
			(layer "B.SilkS")
			(hide yes)
			(effects
				(font
					(size 1.27 1.27)
				)
				(justify mirror)
			)
		)
		(property "Value" ""
			(at 0 0 90)
			(layer "B.Fab")
			(effects
				(font
					(size 1.27 1.27)
				)
				(justify mirror)
			)
		)
		(duplicate_pad_numbers_are_jumpers no)
		(fp_line
			(start 0.7874 -0.4064)
			(end -0.7874 -0.4064)
			(stroke
				(width 0.1524)
				(type default)
			)
			(layer "B.SilkS")
		)
		(fp_line
			(start -0.7874 -0.4064)
			(end -0.7874 0.4064)
			(stroke
				(width 0.1524)
				(type default)
			)
			(layer "B.SilkS")
		)
		(fp_line
			(start 0.7874 0.4064)
			(end 0.7874 -0.4064)
			(stroke
				(width 0.1524)
				(type default)
			)
			(layer "B.SilkS")
		)
		(fp_line
			(start -0.7874 0.4064)
			(end 0.7874 0.4064)
			(stroke
				(width 0.1524)
				(type default)
			)
			(layer "B.SilkS")
		)
		(fp_line
			(start 0.67945 -0.305054)
			(end 0.12065 -0.305054)
			(stroke
				(width 0.1)
				(type default)
			)
			(layer "B.Fab")
		)
		(fp_line
			(start 0.12065 -0.305054)
			(end 0.12065 -0.2794)
			(stroke
				(width 0.1)
				(type default)
			)
			(layer "B.Fab")
		)
		(fp_line
			(start -0.12065 -0.3048)
			(end -0.67945 -0.3048)
			(stroke
				(width 0.1)
				(type default)
			)
			(layer "B.Fab")
		)
		(fp_line
			(start -0.67945 -0.3048)
			(end -0.67945 0.3048)
			(stroke
				(width 0.1)
				(type default)
			)
			(layer "B.Fab")
		)
		(fp_line
			(start 0.12065 -0.2794)
			(end -0.12065 -0.2794)
			(stroke
				(width 0.1)
				(type default)
			)
			(layer "B.Fab")
		)
		(fp_line
			(start -0.12065 -0.2794)
			(end -0.12065 -0.3048)
			(stroke
				(width 0.1)
				(type default)
			)
			(layer "B.Fab")
		)
		(fp_line
			(start 0.12065 0.2794)
			(end 0.12065 0.3048)
			(stroke
				(width 0.1)
				(type default)
			)
			(layer "B.Fab")
		)
		(fp_line
			(start -0.120396 0.2794)
			(end 0.12065 0.2794)
			(stroke
				(width 0.1)
				(type default)
			)
			(layer "B.Fab")
		)
		(fp_line
			(start 0.67945 0.3048)
			(end 0.67945 -0.305054)
			(stroke
				(width 0.1)
				(type default)
			)
			(layer "B.Fab")
		)
		(fp_line
			(start 0.12065 0.3048)
			(end 0.67945 0.3048)
			(stroke
				(width 0.1)
				(type default)
			)
			(layer "B.Fab")
		)
		(fp_line
			(start -0.120396 0.3048)
			(end -0.120396 0.2794)
			(stroke
				(width 0.1)
				(type default)
			)
			(layer "B.Fab")
		)
		(fp_line
			(start -0.67945 0.3048)
			(end -0.120396 0.3048)
			(stroke
				(width 0.1)
				(type default)
			)
			(layer "B.Fab")
		)
		(pad "1" smd circle
			(at 0.40005 0 270)
			(size 0 0)
			(layers "B.Cu" "B.Mask" "B.Paste")
			(net "RST_GPU_PERST_0_BUF_N")
		)
		(pad "2" smd circle
			(at -0.40005 0 270)
			(size 0 0)
			(layers "B.Cu" "B.Mask" "B.Paste")
			(net "RST_GPU_PERST_0_BUF_R_N")
		)
	)
	(footprint ""
		(layer "B.Cu")
		(at 300.399704 -298.27474 180)
		(property "Reference" "C1630"
			(at 0 0 0)
			(layer "B.SilkS")
			(hide yes)
			(effects
				(font
					(size 1.27 1.27)
				)
				(justify mirror)
			)
		)
		(property "Value" ""
			(at 0 0 0)
			(layer "B.Fab")
			(effects
				(font
					(size 1.27 1.27)
				)
				(justify mirror)
			)
		)
		(duplicate_pad_numbers_are_jumpers no)
		(fp_line
			(start 0.299974 0.150114)
			(end 0.299974 -0.150114)
			(stroke
				(width 0.1)
				(type default)
			)
			(layer "B.Fab")
		)
		(fp_line
			(start 0.299974 -0.150114)
			(end -0.299974 -0.150114)
			(stroke
				(width 0.1)
				(type default)
			)
			(layer "B.Fab")
		)
		(fp_line
			(start -0.299974 0.150114)
			(end 0.299974 0.150114)
			(stroke
				(width 0.1)
				(type default)
			)
			(layer "B.Fab")
		)
		(fp_line
			(start -0.299974 -0.150114)
			(end -0.299974 0.150114)
			(stroke
				(width 0.1)
				(type default)
			)
			(layer "B.Fab")
		)
		(pad "1" smd rect
			(at 0.2667 0)
			(size 0.3048 0.381)
			(layers "B.Cu" "B.Mask" "B.Paste")
			(net "P0V8_PEX2")
		)
		(pad "2" smd rect
			(at -0.2667 0)
			(size 0.3048 0.381)
			(layers "B.Cu" "B.Mask" "B.Paste")
			(net "GND")
		)
	)
)
